(kicad_pcb
	(version 20260206)
	(generator "pcbnew")
	(generator_version "10.0")
	(general
		(thickness 1.6)
		(legacy_teardrops no)
	)
	(paper "A4")
	(title_block
		(title "netronome-mezz — pcbd0082-001_rev01_jul9_a.brd")
		(comment 1 "Open CloudServer (Microsoft) / footprints 74-80 of 714")
	)
	(layers
		(0 "F.Cu" signal "TOP")
		(4 "In1.Cu" signal "02_GND")
		(6 "In2.Cu" signal "03_SIG")
		(8 "In3.Cu" signal "04_SIG")
		(10 "In4.Cu" signal "05_GND")
		(12 "In5.Cu" signal "06_PWR1")
		(14 "In6.Cu" signal "07_SIG")
		(16 "In7.Cu" signal "08_SIG")
		(18 "In8.Cu" signal "09_GND")
		(2 "B.Cu" signal "BOTTOM")
		(9 "F.Adhes" user "F.Adhesive")
		(11 "B.Adhes" user "B.Adhesive")
		(13 "F.Paste" user "Package Geometry/Pastemask Top")
		(15 "B.Paste" user "Package Geometry/Pastemask Bottom")
		(5 "F.SilkS" user "Ref Des/Silkscreen Top")
		(7 "B.SilkS" user "Ref Des/Silkscreen Bottom")
		(1 "F.Mask" user "Board Geometry/Soldermask Top")
		(3 "B.Mask" user "Board Geometry/Soldermask Bottom")
		(17 "Dwgs.User" user "User.Drawings")
		(19 "Cmts.User" user "User.Comments")
		(21 "Eco1.User" user "User.Eco1")
		(23 "Eco2.User" user "User.Eco2")
		(25 "Edge.Cuts" user "Board Geometry/Outline")
		(27 "Margin" user)
		(31 "F.CrtYd" user "Package Geometry/Place Bound Top")
		(29 "B.CrtYd" user "Package Geometry/Place Bound Bottom")
		(35 "F.Fab" user "Ref Des/Assembly Top")
		(33 "B.Fab" user "Ref Des/Assembly Bottom")
		(45 "User.4" user "COMPVAL_TYPE_BOTTOM")
	)
	(footprint ""
		(layer "F.Cu")
		(at 23.6601 1.397 -90)
		(property "Reference" "R383"
			(at -0.86233 0.8001 0)
			(unlocked yes)
			(layer "F.SilkS")
			(effects
				(font
					(size 0.7874 0.5842)
					(thickness 0.127)
				)
				(justify left)
			)
		)
		(property "Value" "0"
			(at -0.148158 1.3462 0)
			(unlocked yes)
			(layer "F.Fab")
			(hide yes)
			(effects
				(font
					(size 1.27 0.9652)
					(thickness 0.000001)
				)
				(justify left)
			)
		)
		(property "Device Type" "REST1111"
			(at -0.148158 1.3462 0)
			(unlocked yes)
			(layer "F.Fab")
			(hide yes)
			(effects
				(font
					(size 1.27 0.9652)
					(thickness 0.000001)
				)
				(justify left)
			)
		)
		(duplicate_pad_numbers_are_jumpers no)
		(fp_poly
			(pts
				(xy 0.635 1.0668) (xy 0.635 -1.0668) (xy -0.635 -1.0668) (xy -0.635 1.0668)
			)
			(stroke
				(width 0)
				(type default)
			)
			(fill no)
			(layer "F.CrtYd")
		)
		(fp_line
			(start -0.254 0.508)
			(end -0.254 -0.508)
			(stroke
				(width 0.0254)
				(type default)
			)
			(layer "F.Fab")
		)
		(fp_line
			(start 0.254 0.508)
			(end -0.254 0.508)
			(stroke
				(width 0.0254)
				(type default)
			)
			(layer "F.Fab")
		)
		(fp_line
			(start -0.254 -0.508)
			(end 0.254 -0.508)
			(stroke
				(width 0.0254)
				(type default)
			)
			(layer "F.Fab")
		)
		(fp_line
			(start 0.254 -0.508)
			(end 0.254 0.508)
			(stroke
				(width 0.0254)
				(type default)
			)
			(layer "F.Fab")
		)
		(pad "1" smd rect
			(at 0 -0.4191 270)
			(size 0.508 0.5334)
			(layers "F.Cu" "F.Mask" "F.Paste")
			(net "NFP_SMBUS_SCL")
		)
		(pad "2" smd rect
			(at 0 0.4191 270)
			(size 0.508 0.5334)
			(layers "F.Cu" "F.Mask" "F.Paste")
			(net "MUX_NFP_SMBUS_SCL")
		)
		(zone
			(layer "F.Cu")
			(hatch none 0.5)
			(connect_pads
				(clearance 0)
			)
			(min_thickness 0.25)
			(keepout
				(tracks not_allowed)
				(vias allowed)
				(pads allowed)
				(copperpour not_allowed)
				(footprints allowed)
			)
			(placement
				(enabled no)
				(sheetname "")
			)
			(fill
				(thermal_gap 0.5)
				(thermal_bridge_width 0.5)
				(island_removal_mode 0)
			)
			(polygon
				(pts
					(xy 23.6855 1.4224) (xy 23.6347 1.4224) (xy 23.6347 1.3716) (xy 23.6855 1.3716)
				)
			)
		)
	)
	(footprint ""
		(layer "F.Cu")
		(at 10.16 1.397)
		(property "Reference" "R367"
			(at 0.196012 -1.4732 90)
			(unlocked yes)
			(layer "F.SilkS")
			(effects
				(font
					(size 0.7874 0.5842)
					(thickness 0.127)
				)
				(justify left)
			)
		)
		(property "Value" "0"
			(at -0.148158 1.3462 90)
			(unlocked yes)
			(layer "F.Fab")
			(hide yes)
			(effects
				(font
					(size 1.27 0.9652)
					(thickness 0.000001)
				)
				(justify left)
			)
		)
		(property "Device Type" "REST1111"
			(at -0.148158 1.3462 90)
			(unlocked yes)
			(layer "F.Fab")
			(hide yes)
			(effects
				(font
					(size 1.27 0.9652)
					(thickness 0.000001)
				)
				(justify left)
			)
		)
		(duplicate_pad_numbers_are_jumpers no)
		(fp_poly
			(pts
				(xy 0.635 1.0668) (xy 0.635 -1.0668) (xy -0.635 -1.0668) (xy -0.635 1.0668)
			)
			(stroke
				(width 0)
				(type default)
			)
			(fill no)
			(layer "F.CrtYd")
		)
		(fp_line
			(start -0.254 -0.508)
			(end 0.254 -0.508)
			(stroke
				(width 0.0254)
				(type default)
			)
			(layer "F.Fab")
		)
		(fp_line
			(start -0.254 0.508)
			(end -0.254 -0.508)
			(stroke
				(width 0.0254)
				(type default)
			)
			(layer "F.Fab")
		)
		(fp_line
			(start 0.254 -0.508)
			(end 0.254 0.508)
			(stroke
				(width 0.0254)
				(type default)
			)
			(layer "F.Fab")
		)
		(fp_line
			(start 0.254 0.508)
			(end -0.254 0.508)
			(stroke
				(width 0.0254)
				(type default)
			)
			(layer "F.Fab")
		)
		(pad "1" smd rect
			(at 0 -0.4191)
			(size 0.508 0.5334)
			(layers "F.Cu" "F.Mask" "F.Paste")
			(net "CPLD_PCIE0_WAKE_L")
		)
		(pad "2" smd rect
			(at 0 0.4191)
			(size 0.508 0.5334)
			(layers "F.Cu" "F.Mask" "F.Paste")
			(net "PCIE0_WAKE_L")
		)
		(zone
			(layer "F.Cu")
			(hatch none 0.5)
			(connect_pads
				(clearance 0)
			)
			(min_thickness 0.25)
			(keepout
				(tracks not_allowed)
				(vias allowed)
				(pads allowed)
				(copperpour not_allowed)
				(footprints allowed)
			)
			(placement
				(enabled no)
				(sheetname "")
			)
			(fill
				(thermal_gap 0.5)
				(thermal_bridge_width 0.5)
				(island_removal_mode 0)
			)
			(polygon
				(pts
					(xy 10.1854 1.3716) (xy 10.1854 1.4224) (xy 10.1346 1.4224) (xy 10.1346 1.3716)
				)
			)
		)
	)
	(footprint ""
		(layer "F.Cu")
		(at 81.026 28.702 180)
		(property "Reference" "R223"
			(at 0 0 180)
			(layer "F.SilkS")
			(hide yes)
			(effects
				(font
					(size 1.27 1.27)
				)
			)
		)
		(property "Value" "39.0"
			(at -0.148158 1.3462 270)
			(unlocked yes)
			(layer "F.Fab")
			(hide yes)
			(effects
				(font
					(size 1.27 0.9652)
					(thickness 0.000001)
				)
				(justify left)
			)
		)
		(property "Device Type" "REST0108"
			(at -0.148158 1.3462 270)
			(unlocked yes)
			(layer "F.Fab")
			(hide yes)
			(effects
				(font
					(size 1.27 0.9652)
					(thickness 0.000001)
				)
				(justify left)
			)
		)
		(duplicate_pad_numbers_are_jumpers no)
		(fp_poly
			(pts
				(xy 0.635 1.0668) (xy 0.635 -1.0668) (xy -0.635 -1.0668) (xy -0.635 1.0668)
			)
			(stroke
				(width 0)
				(type default)
			)
			(fill no)
			(layer "F.CrtYd")
		)
		(fp_line
			(start 0.254 0.508)
			(end -0.254 0.508)
			(stroke
				(width 0.0254)
				(type default)
			)
			(layer "F.Fab")
		)
		(fp_line
			(start 0.254 -0.508)
			(end 0.254 0.508)
			(stroke
				(width 0.0254)
				(type default)
			)
			(layer "F.Fab")
		)
		(fp_line
			(start -0.254 0.508)
			(end -0.254 -0.508)
			(stroke
				(width 0.0254)
				(type default)
			)
			(layer "F.Fab")
		)
		(fp_line
			(start -0.254 -0.508)
			(end 0.254 -0.508)
			(stroke
				(width 0.0254)
				(type default)
			)
			(layer "F.Fab")
		)
		(pad "1" smd rect
			(at 0 -0.4191 180)
			(size 0.508 0.5334)
			(layers "F.Cu" "F.Mask" "F.Paste")
			(net "DDR0_32A_BA1")
		)
		(pad "2" smd rect
			(at 0 0.4191 180)
			(size 0.508 0.5334)
			(layers "F.Cu" "F.Mask" "F.Paste")
			(net "DDR_VTT")
		)
		(zone
			(layer "F.Cu")
			(hatch none 0.5)
			(connect_pads
				(clearance 0)
			)
			(min_thickness 0.25)
			(keepout
				(tracks not_allowed)
				(vias allowed)
				(pads allowed)
				(copperpour not_allowed)
				(footprints allowed)
			)
			(placement
				(enabled no)
				(sheetname "")
			)
			(fill
				(thermal_gap 0.5)
				(thermal_bridge_width 0.5)
				(island_removal_mode 0)
			)
			(polygon
				(pts
					(xy 81.0006 28.7274) (xy 81.0006 28.6766) (xy 81.0514 28.6766) (xy 81.0514 28.7274)
				)
			)
		)
	)
	(footprint ""
		(layer "F.Cu")
		(at 84.582 28.702 180)
		(property "Reference" "R220"
			(at -0.91567 -1.651 90)
			(unlocked yes)
			(layer "F.SilkS")
			(effects
				(font
					(size 0.7874 0.5842)
					(thickness 0.127)
				)
				(justify left)
			)
		)
		(property "Value" "39.0"
			(at -0.148158 1.3462 270)
			(unlocked yes)
			(layer "F.Fab")
			(hide yes)
			(effects
				(font
					(size 1.27 0.9652)
					(thickness 0.000001)
				)
				(justify left)
			)
		)
		(property "Device Type" "REST0108"
			(at -0.148158 1.3462 270)
			(unlocked yes)
			(layer "F.Fab")
			(hide yes)
			(effects
				(font
					(size 1.27 0.9652)
					(thickness 0.000001)
				)
				(justify left)
			)
		)
		(duplicate_pad_numbers_are_jumpers no)
		(fp_poly
			(pts
				(xy 0.635 1.0668) (xy 0.635 -1.0668) (xy -0.635 -1.0668) (xy -0.635 1.0668)
			)
			(stroke
				(width 0)
				(type default)
			)
			(fill no)
			(layer "F.CrtYd")
		)
		(fp_line
			(start 0.254 0.508)
			(end -0.254 0.508)
			(stroke
				(width 0.0254)
				(type default)
			)
			(layer "F.Fab")
		)
		(fp_line
			(start 0.254 -0.508)
			(end 0.254 0.508)
			(stroke
				(width 0.0254)
				(type default)
			)
			(layer "F.Fab")
		)
		(fp_line
			(start -0.254 0.508)
			(end -0.254 -0.508)
			(stroke
				(width 0.0254)
				(type default)
			)
			(layer "F.Fab")
		)
		(fp_line
			(start -0.254 -0.508)
			(end 0.254 -0.508)
			(stroke
				(width 0.0254)
				(type default)
			)
			(layer "F.Fab")
		)
		(pad "1" smd rect
			(at 0 -0.4191 180)
			(size 0.508 0.5334)
			(layers "F.Cu" "F.Mask" "F.Paste")
			(net "DDR0_32A_A14")
		)
		(pad "2" smd rect
			(at 0 0.4191 180)
			(size 0.508 0.5334)
			(layers "F.Cu" "F.Mask" "F.Paste")
			(net "DDR_VTT")
		)
		(zone
			(layer "F.Cu")
			(hatch none 0.5)
			(connect_pads
				(clearance 0)
			)
			(min_thickness 0.25)
			(keepout
				(tracks not_allowed)
				(vias allowed)
				(pads allowed)
				(copperpour not_allowed)
				(footprints allowed)
			)
			(placement
				(enabled no)
				(sheetname "")
			)
			(fill
				(thermal_gap 0.5)
				(thermal_bridge_width 0.5)
				(island_removal_mode 0)
			)
			(polygon
				(pts
					(xy 84.5566 28.7274) (xy 84.5566 28.6766) (xy 84.6074 28.6766) (xy 84.6074 28.7274)
				)
			)
		)
	)
	(footprint ""
		(layer "F.Cu")
		(at 77.978 9.271 90)
		(property "Reference" "R189"
			(at 0 0 90)
			(layer "F.SilkS")
			(hide yes)
			(effects
				(font
					(size 1.27 1.27)
				)
			)
		)
		(property "Value" "240"
			(at -0.148158 1.3462 180)
			(unlocked yes)
			(layer "F.Fab")
			(hide yes)
			(effects
				(font
					(size 1.27 0.9652)
					(thickness 0.000001)
				)
				(justify left)
			)
		)
		(property "Device Type" "REST0009"
			(at -0.148158 1.3462 180)
			(unlocked yes)
			(layer "F.Fab")
			(hide yes)
			(effects
				(font
					(size 1.27 0.9652)
					(thickness 0.000001)
				)
				(justify left)
			)
		)
		(duplicate_pad_numbers_are_jumpers no)
		(fp_poly
			(pts
				(xy 0.635 1.0668) (xy 0.635 -1.0668) (xy -0.635 -1.0668) (xy -0.635 1.0668)
			)
			(stroke
				(width 0)
				(type default)
			)
			(fill no)
			(layer "F.CrtYd")
		)
		(fp_line
			(start 0.254 -0.508)
			(end 0.254 0.508)
			(stroke
				(width 0.0254)
				(type default)
			)
			(layer "F.Fab")
		)
		(fp_line
			(start -0.254 -0.508)
			(end 0.254 -0.508)
			(stroke
				(width 0.0254)
				(type default)
			)
			(layer "F.Fab")
		)
		(fp_line
			(start 0.254 0.508)
			(end -0.254 0.508)
			(stroke
				(width 0.0254)
				(type default)
			)
			(layer "F.Fab")
		)
		(fp_line
			(start -0.254 0.508)
			(end -0.254 -0.508)
			(stroke
				(width 0.0254)
				(type default)
			)
			(layer "F.Fab")
		)
		(pad "1" smd rect
			(at 0 -0.4191 90)
			(size 0.508 0.5334)
			(layers "F.Cu" "F.Mask" "F.Paste")
			(net "GND")
		)
		(pad "2" smd rect
			(at 0 0.4191 90)
			(size 0.508 0.5334)
			(layers "F.Cu" "F.Mask" "F.Paste")
			(net "12N2312")
		)
		(zone
			(layer "F.Cu")
			(hatch none 0.5)
			(connect_pads
				(clearance 0)
			)
			(min_thickness 0.25)
			(keepout
				(tracks not_allowed)
				(vias allowed)
				(pads allowed)
				(copperpour not_allowed)
				(footprints allowed)
			)
			(placement
				(enabled no)
				(sheetname "")
			)
			(fill
				(thermal_gap 0.5)
				(thermal_bridge_width 0.5)
				(island_removal_mode 0)
			)
			(polygon
				(pts
					(xy 77.9526 9.2456) (xy 78.0034 9.2456) (xy 78.0034 9.2964) (xy 77.9526 9.2964)
				)
			)
		)
	)
	(footprint ""
		(layer "F.Cu")
		(at 77.851 53.975 180)
		(property "Reference" "C184"
			(at -2.94767 -1.524 90)
			(unlocked yes)
			(layer "F.SilkS")
			(effects
				(font
					(size 0.7874 0.5842)
					(thickness 0.127)
				)
				(justify left)
			)
		)
		(property "Value" ""
			(at 0 0 180)
			(layer "F.Fab")
			(effects
				(font
					(size 1.27 1.27)
				)
			)
		)
		(duplicate_pad_numbers_are_jumpers no)
		(fp_arc
			(start 0.381 0.336017)
			(mid 0.20901 0.463015)
			(end 0 0.508)
			(stroke
				(width 0.2032)
				(type default)
			)
			(layer "F.SilkS")
		)
		(fp_arc
			(start 0 0.508)
			(mid -0.209008 0.463011)
			(end -0.381 0.336017)
			(stroke
				(width 0.2032)
				(type default)
			)
			(layer "F.SilkS")
		)
		(fp_arc
			(start 0 -0.508)
			(mid 0.209 -0.463015)
			(end 0.381 -0.336042)
			(stroke
				(width 0.2032)
				(type default)
			)
			(layer "F.SilkS")
		)
		(fp_arc
			(start -0.381 -0.335991)
			(mid -0.209012 -0.462996)
			(end 0 -0.508)
			(stroke
				(width 0.2032)
				(type default)
			)
			(layer "F.SilkS")
		)
		(fp_circle
			(center 0 0)
			(end -0.508 0)
			(stroke
				(width 0.2032)
				(type default)
			)
			(fill no)
			(layer "F.SilkS")
		)
		(fp_poly
			(pts
				(xy -2.286 1.778) (xy -2.286 -1.524) (xy 2.286 -1.524) (xy 2.286 1.778)
			)
			(stroke
				(width 0)
				(type default)
			)
			(fill no)
			(layer "F.CrtYd")
		)
		(fp_line
			(start 1.524 1.27)
			(end -1.524 1.27)
			(stroke
				(width 0.0254)
				(type default)
			)
			(layer "F.Fab")
		)
		(fp_line
			(start 1.524 -1.27)
			(end 1.524 1.27)
			(stroke
				(width 0.0254)
				(type default)
			)
			(layer "F.Fab")
		)
		(fp_line
			(start -1.524 1.27)
			(end -1.524 -1.27)
			(stroke
				(width 0.0254)
				(type default)
			)
			(layer "F.Fab")
		)
		(fp_line
			(start -1.524 -1.27)
			(end 1.524 -1.27)
			(stroke
				(width 0.0254)
				(type default)
			)
			(layer "F.Fab")
		)
		(pad "1" smd rect
			(at -1.4224 0 270)
			(size 2.7432 1.3716)
			(layers "F.Cu" "F.Mask" "F.Paste")
			(net "EXT_12.0V")
		)
		(pad "2" smd rect
			(at 1.4224 0 270)
			(size 2.7432 1.3716)
			(layers "F.Cu" "F.Mask" "F.Paste")
			(net "GND")
		)
	)
	(footprint ""
		(layer "F.Cu")
		(at 28.575 7.112 90)
		(property "Reference" "R15"
			(at 0.86233 -1.016 0)
			(unlocked yes)
			(layer "F.SilkS")
			(effects
				(font
					(size 0.7874 0.5842)
					(thickness 0.127)
				)
				(justify left)
			)
		)
		(property "Value" "4.75K"
			(at -0.148158 1.3462 180)
			(unlocked yes)
			(layer "F.Fab")
			(hide yes)
			(effects
				(font
					(size 1.27 0.9652)
					(thickness 0.000001)
				)
				(justify left)
			)
		)
		(property "Device Type" "REST4024"
			(at -0.148158 1.3462 180)
			(unlocked yes)
			(layer "F.Fab")
			(hide yes)
			(effects
				(font
					(size 1.27 0.9652)
					(thickness 0.000001)
				)
				(justify left)
			)
		)
		(duplicate_pad_numbers_are_jumpers no)
		(fp_poly
			(pts
				(xy 0.635 1.0668) (xy 0.635 -1.0668) (xy -0.635 -1.0668) (xy -0.635 1.0668)
			)
			(stroke
				(width 0)
				(type default)
			)
			(fill no)
			(layer "F.CrtYd")
		)
		(fp_line
			(start 0.254 -0.508)
			(end 0.254 0.508)
			(stroke
				(width 0.0254)
				(type default)
			)
			(layer "F.Fab")
		)
		(fp_line
			(start -0.254 -0.508)
			(end 0.254 -0.508)
			(stroke
				(width 0.0254)
				(type default)
			)
			(layer "F.Fab")
		)
		(fp_line
			(start 0.254 0.508)
			(end -0.254 0.508)
			(stroke
				(width 0.0254)
				(type default)
			)
			(layer "F.Fab")
		)
		(fp_line
			(start -0.254 0.508)
			(end -0.254 -0.508)
			(stroke
				(width 0.0254)
				(type default)
			)
			(layer "F.Fab")
		)
		(pad "1" smd rect
			(at 0 -0.4191 90)
			(size 0.508 0.5334)
			(layers "F.Cu" "F.Mask" "F.Paste")
			(net "EXT_3.3V")
		)
		(pad "2" smd rect
			(at 0 0.4191 90)
			(size 0.508 0.5334)
			(layers "F.Cu" "F.Mask" "F.Paste")
			(net "3N2286")
		)
		(zone
			(layer "F.Cu")
			(hatch none 0.5)
			(connect_pads
				(clearance 0)
			)
			(min_thickness 0.25)
			(keepout
				(tracks not_allowed)
				(vias allowed)
				(pads allowed)
				(copperpour not_allowed)
				(footprints allowed)
			)
			(placement
				(enabled no)
				(sheetname "")
			)
			(fill
				(thermal_gap 0.5)
				(thermal_bridge_width 0.5)
				(island_removal_mode 0)
			)
			(polygon
				(pts
					(xy 28.5496 7.0866) (xy 28.6004 7.0866) (xy 28.6004 7.1374) (xy 28.5496 7.1374)
				)
			)
		)
	)
)
